(kicad_pcb
	(version 20260206)
	(generator "pcbnew")
	(generator_version "10.0")
	(general
		(thickness 1.6)
		(legacy_teardrops no)
	)
	(paper "A4")
	(title_block
		(title "03242023_DA0F0TMBIJ0_F0T_Motherboard_J_brd_V01_OCP.brd")
		(comment 1 "Grand Teton / footprints 1560-1566 of 6105")
	)
	(layers
		(0 "F.Cu" signal "TOP")
		(4 "In1.Cu" signal "GND")
		(6 "In2.Cu" signal "IN1")
		(8 "In3.Cu" signal "GND1")
		(10 "In4.Cu" signal "IN2")
		(12 "In5.Cu" signal "GND2")
		(14 "In6.Cu" signal "IN3")
		(16 "In7.Cu" signal "GND3")
		(18 "In8.Cu" signal "VCC")
		(20 "In9.Cu" signal "VCC1")
		(22 "In10.Cu" signal "GND4")
		(24 "In11.Cu" signal "IN4")
		(26 "In12.Cu" signal "GND5")
		(28 "In13.Cu" signal "IN5")
		(30 "In14.Cu" signal "GND6")
		(32 "In15.Cu" signal "IN6")
		(34 "In16.Cu" signal "GND7")
		(2 "B.Cu" signal "BOTTOM")
		(9 "F.Adhes" user "F.Adhesive")
		(11 "B.Adhes" user "B.Adhesive")
		(13 "F.Paste" user "Package Geometry/Pastemask Top")
		(15 "B.Paste" user "Package Geometry/Pastemask Bottom")
		(5 "F.SilkS" user "Ref Des/Silkscreen Top")
		(7 "B.SilkS" user "Ref Des/Silkscreen Bottom")
		(1 "F.Mask" user "Board Geometry/Soldermask Top")
		(3 "B.Mask" user "Board Geometry/Soldermask Bottom")
		(17 "Dwgs.User" user "User.Drawings")
		(19 "Cmts.User" user "User.Comments")
		(21 "Eco1.User" user "User.Eco1")
		(23 "Eco2.User" user "User.Eco2")
		(25 "Edge.Cuts" user "Board Geometry/Outline")
		(27 "Margin" user)
		(31 "F.CrtYd" user "Package Geometry/Place Bound Top")
		(29 "B.CrtYd" user "Package Geometry/Place Bound Bottom")
		(35 "F.Fab" user "Ref Des/Assembly Top")
		(33 "B.Fab" user "Ref Des/Assembly Bottom")
	)
	(footprint ""
		(layer "F.Cu")
		(at 220.190822 -56.835802 180)
		(property "Reference" "R3760"
			(at 0 0 180)
			(layer "F.SilkS")
			(hide yes)
			(effects
				(font
					(size 1.27 1.27)
				)
			)
		)
		(property "Value" ""
			(at 0 0 180)
			(layer "F.Fab")
			(effects
				(font
					(size 1.27 1.27)
				)
			)
		)
		(duplicate_pad_numbers_are_jumpers no)
		(fp_line
			(start 0.7874 0.4064)
			(end -0.7874 0.4064)
			(stroke
				(width 0.1524)
				(type default)
			)
			(layer "F.SilkS")
		)
		(fp_line
			(start 0.7874 -0.4064)
			(end 0.7874 0.4064)
			(stroke
				(width 0.1524)
				(type default)
			)
			(layer "F.SilkS")
		)
		(fp_line
			(start -0.7874 0.4064)
			(end -0.7874 -0.4064)
			(stroke
				(width 0.1524)
				(type default)
			)
			(layer "F.SilkS")
		)
		(fp_line
			(start -0.7874 -0.4064)
			(end 0.7874 -0.4064)
			(stroke
				(width 0.1524)
				(type default)
			)
			(layer "F.SilkS")
		)
		(fp_line
			(start 0.67945 0.3048)
			(end 0.120396 0.3048)
			(stroke
				(width 0.1)
				(type default)
			)
			(layer "F.Fab")
		)
		(fp_line
			(start 0.67945 -0.3048)
			(end 0.67945 0.3048)
			(stroke
				(width 0.1)
				(type default)
			)
			(layer "F.Fab")
		)
		(fp_line
			(start 0.12065 -0.2794)
			(end 0.12065 -0.3048)
			(stroke
				(width 0.1)
				(type default)
			)
			(layer "F.Fab")
		)
		(fp_line
			(start 0.12065 -0.3048)
			(end 0.67945 -0.3048)
			(stroke
				(width 0.1)
				(type default)
			)
			(layer "F.Fab")
		)
		(fp_line
			(start 0.120396 0.3048)
			(end 0.120396 0.2794)
			(stroke
				(width 0.1)
				(type default)
			)
			(layer "F.Fab")
		)
		(fp_line
			(start 0.120396 0.2794)
			(end -0.12065 0.2794)
			(stroke
				(width 0.1)
				(type default)
			)
			(layer "F.Fab")
		)
		(fp_line
			(start -0.12065 0.3048)
			(end -0.67945 0.3048)
			(stroke
				(width 0.1)
				(type default)
			)
			(layer "F.Fab")
		)
		(fp_line
			(start -0.12065 0.2794)
			(end -0.12065 0.3048)
			(stroke
				(width 0.1)
				(type default)
			)
			(layer "F.Fab")
		)
		(fp_line
			(start -0.12065 -0.2794)
			(end 0.12065 -0.2794)
			(stroke
				(width 0.1)
				(type default)
			)
			(layer "F.Fab")
		)
		(fp_line
			(start -0.12065 -0.305054)
			(end -0.12065 -0.2794)
			(stroke
				(width 0.1)
				(type default)
			)
			(layer "F.Fab")
		)
		(fp_line
			(start -0.67945 0.3048)
			(end -0.67945 -0.305054)
			(stroke
				(width 0.1)
				(type default)
			)
			(layer "F.Fab")
		)
		(fp_line
			(start -0.67945 -0.305054)
			(end -0.12065 -0.305054)
			(stroke
				(width 0.1)
				(type default)
			)
			(layer "F.Fab")
		)
		(pad "1" smd circle
			(at -0.40005 0 180)
			(size 0 0)
			(layers "F.Cu" "F.Mask" "F.Paste")
			(net "P3V3_E1S_0")
		)
		(pad "2" smd circle
			(at 0.40005 0 180)
			(size 0 0)
			(layers "F.Cu" "F.Mask" "F.Paste")
			(net "VSENSE_P3V3_INA230_2_INN")
		)
	)
	(footprint ""
		(layer "F.Cu")
		(at 387.526022 -347.520514 -90)
		(property "Reference" "PC234"
			(at 0 0 270)
			(layer "F.SilkS")
			(hide yes)
			(effects
				(font
					(size 1.27 1.27)
				)
			)
		)
		(property "Value" ""
			(at 0 0 270)
			(layer "F.Fab")
			(effects
				(font
					(size 1.27 1.27)
				)
			)
		)
		(duplicate_pad_numbers_are_jumpers no)
		(fp_line
			(start -0.7874 0.4064)
			(end -0.7874 -0.4064)
			(stroke
				(width 0.1524)
				(type default)
			)
			(layer "F.SilkS")
		)
		(fp_line
			(start 0.7874 0.4064)
			(end -0.7874 0.4064)
			(stroke
				(width 0.1524)
				(type default)
			)
			(layer "F.SilkS")
		)
		(fp_line
			(start -0.7874 -0.4064)
			(end 0.7874 -0.4064)
			(stroke
				(width 0.1524)
				(type default)
			)
			(layer "F.SilkS")
		)
		(fp_line
			(start 0.7874 -0.4064)
			(end 0.7874 0.4064)
			(stroke
				(width 0.1524)
				(type default)
			)
			(layer "F.SilkS")
		)
		(fp_line
			(start -0.67945 0.3048)
			(end -0.67945 -0.305054)
			(stroke
				(width 0.1)
				(type default)
			)
			(layer "F.Fab")
		)
		(fp_line
			(start -0.12065 0.3048)
			(end -0.67945 0.3048)
			(stroke
				(width 0.1)
				(type default)
			)
			(layer "F.Fab")
		)
		(fp_line
			(start 0.120396 0.3048)
			(end 0.120396 0.2794)
			(stroke
				(width 0.1)
				(type default)
			)
			(layer "F.Fab")
		)
		(fp_line
			(start 0.67945 0.3048)
			(end 0.120396 0.3048)
			(stroke
				(width 0.1)
				(type default)
			)
			(layer "F.Fab")
		)
		(fp_line
			(start -0.12065 0.2794)
			(end -0.12065 0.3048)
			(stroke
				(width 0.1)
				(type default)
			)
			(layer "F.Fab")
		)
		(fp_line
			(start 0.120396 0.2794)
			(end -0.12065 0.2794)
			(stroke
				(width 0.1)
				(type default)
			)
			(layer "F.Fab")
		)
		(fp_line
			(start -0.12065 -0.2794)
			(end 0.12065 -0.2794)
			(stroke
				(width 0.1)
				(type default)
			)
			(layer "F.Fab")
		)
		(fp_line
			(start 0.12065 -0.2794)
			(end 0.12065 -0.3048)
			(stroke
				(width 0.1)
				(type default)
			)
			(layer "F.Fab")
		)
		(fp_line
			(start 0.12065 -0.3048)
			(end 0.67945 -0.3048)
			(stroke
				(width 0.1)
				(type default)
			)
			(layer "F.Fab")
		)
		(fp_line
			(start 0.67945 -0.3048)
			(end 0.67945 0.3048)
			(stroke
				(width 0.1)
				(type default)
			)
			(layer "F.Fab")
		)
		(fp_line
			(start -0.67945 -0.305054)
			(end -0.12065 -0.305054)
			(stroke
				(width 0.1)
				(type default)
			)
			(layer "F.Fab")
		)
		(fp_line
			(start -0.12065 -0.305054)
			(end -0.12065 -0.2794)
			(stroke
				(width 0.1)
				(type default)
			)
			(layer "F.Fab")
		)
		(pad "1" smd circle
			(at -0.40005 0 270)
			(size 0 0)
			(layers "F.Cu" "F.Mask" "F.Paste")
			(net "SW_PVCCIN_CPU0_BOOT8_R")
		)
		(pad "2" smd circle
			(at 0.40005 0 270)
			(size 0 0)
			(layers "F.Cu" "F.Mask" "F.Paste")
			(net "SW_PVCCIN_CPU0_BOOTR8")
		)
	)
	(footprint ""
		(layer "F.Cu")
		(at 164.247576 -38.067234 180)
		(property "Reference" "R4457"
			(at 0 0 180)
			(layer "F.SilkS")
			(hide yes)
			(effects
				(font
					(size 1.27 1.27)
				)
			)
		)
		(property "Value" ""
			(at 0 0 180)
			(layer "F.Fab")
			(effects
				(font
					(size 1.27 1.27)
				)
			)
		)
		(duplicate_pad_numbers_are_jumpers no)
		(fp_line
			(start 0.7874 0.4064)
			(end -0.7874 0.4064)
			(stroke
				(width 0.1524)
				(type default)
			)
			(layer "F.SilkS")
		)
		(fp_line
			(start 0.7874 -0.4064)
			(end 0.7874 0.4064)
			(stroke
				(width 0.1524)
				(type default)
			)
			(layer "F.SilkS")
		)
		(fp_line
			(start -0.7874 0.4064)
			(end -0.7874 -0.4064)
			(stroke
				(width 0.1524)
				(type default)
			)
			(layer "F.SilkS")
		)
		(fp_line
			(start -0.7874 -0.4064)
			(end 0.7874 -0.4064)
			(stroke
				(width 0.1524)
				(type default)
			)
			(layer "F.SilkS")
		)
		(fp_line
			(start 0.67945 0.3048)
			(end 0.120396 0.3048)
			(stroke
				(width 0.1)
				(type default)
			)
			(layer "F.Fab")
		)
		(fp_line
			(start 0.67945 -0.3048)
			(end 0.67945 0.3048)
			(stroke
				(width 0.1)
				(type default)
			)
			(layer "F.Fab")
		)
		(fp_line
			(start 0.12065 -0.2794)
			(end 0.12065 -0.3048)
			(stroke
				(width 0.1)
				(type default)
			)
			(layer "F.Fab")
		)
		(fp_line
			(start 0.12065 -0.3048)
			(end 0.67945 -0.3048)
			(stroke
				(width 0.1)
				(type default)
			)
			(layer "F.Fab")
		)
		(fp_line
			(start 0.120396 0.3048)
			(end 0.120396 0.2794)
			(stroke
				(width 0.1)
				(type default)
			)
			(layer "F.Fab")
		)
		(fp_line
			(start 0.120396 0.2794)
			(end -0.12065 0.2794)
			(stroke
				(width 0.1)
				(type default)
			)
			(layer "F.Fab")
		)
		(fp_line
			(start -0.12065 0.3048)
			(end -0.67945 0.3048)
			(stroke
				(width 0.1)
				(type default)
			)
			(layer "F.Fab")
		)
		(fp_line
			(start -0.12065 0.2794)
			(end -0.12065 0.3048)
			(stroke
				(width 0.1)
				(type default)
			)
			(layer "F.Fab")
		)
		(fp_line
			(start -0.12065 -0.2794)
			(end 0.12065 -0.2794)
			(stroke
				(width 0.1)
				(type default)
			)
			(layer "F.Fab")
		)
		(fp_line
			(start -0.12065 -0.305054)
			(end -0.12065 -0.2794)
			(stroke
				(width 0.1)
				(type default)
			)
			(layer "F.Fab")
		)
		(fp_line
			(start -0.67945 0.3048)
			(end -0.67945 -0.305054)
			(stroke
				(width 0.1)
				(type default)
			)
			(layer "F.Fab")
		)
		(fp_line
			(start -0.67945 -0.305054)
			(end -0.12065 -0.305054)
			(stroke
				(width 0.1)
				(type default)
			)
			(layer "F.Fab")
		)
		(pad "1" smd circle
			(at -0.40005 0 180)
			(size 0 0)
			(layers "F.Cu" "F.Mask" "F.Paste")
			(net "P3V3_AUX")
		)
		(pad "2" smd circle
			(at 0.40005 0 180)
			(size 0 0)
			(layers "F.Cu" "F.Mask" "F.Paste")
			(net "USB_HUB_2_OVCUR2")
		)
	)
	(footprint ""
		(layer "F.Cu")
		(at 277.894796 -153.76652)
		(property "Reference" "H122"
			(at -2.5527 -8.20293 0)
			(unlocked yes)
			(layer "F.SilkS")
			(effects
				(font
					(size 0.7874 0.5842)
					(thickness 0.1524)
				)
				(justify left)
			)
		)
		(property "Value" ""
			(at 0 0 0)
			(layer "F.Fab")
			(effects
				(font
					(size 1.27 1.27)
				)
			)
		)
		(duplicate_pad_numbers_are_jumpers no)
		(fp_circle
			(center 0 0)
			(end 5.8166 0)
			(stroke
				(width 0.1524)
				(type default)
			)
			(fill no)
			(layer "F.SilkS")
		)
		(fp_circle
			(center 0 0)
			(end 5.8166 0)
			(stroke
				(width 0.1524)
				(type default)
			)
			(fill no)
			(layer "B.SilkS")
		)
		(fp_circle
			(center 0 0)
			(end 5.8166 0)
			(stroke
				(width 0.1)
				(type default)
			)
			(fill no)
			(layer "B.Fab")
		)
		(fp_circle
			(center 0 0)
			(end 5.8166 0)
			(stroke
				(width 0.1)
				(type default)
			)
			(fill no)
			(layer "F.Fab")
		)
		(pad "" np_thru_hole circle
			(at 0 0)
			(size 10.0076 10.0076)
			(drill 10.0076)
			(layers "*.Cu" "*.Mask")
			(clearance 0.381)
			(thermal_gap 0.381)
		)
	)
	(footprint ""
		(layer "F.Cu")
		(at 333.986124 -25.956006 -90)
		(property "Reference" "R1868"
			(at 0 0 270)
			(layer "F.SilkS")
			(hide yes)
			(effects
				(font
					(size 1.27 1.27)
				)
			)
		)
		(property "Value" ""
			(at 0 0 270)
			(layer "F.Fab")
			(effects
				(font
					(size 1.27 1.27)
				)
			)
		)
		(duplicate_pad_numbers_are_jumpers no)
		(fp_line
			(start -0.7874 0.4064)
			(end -0.7874 -0.4064)
			(stroke
				(width 0.1524)
				(type default)
			)
			(layer "F.SilkS")
		)
		(fp_line
			(start 0.7874 0.4064)
			(end -0.7874 0.4064)
			(stroke
				(width 0.1524)
				(type default)
			)
			(layer "F.SilkS")
		)
		(fp_line
			(start -0.7874 -0.4064)
			(end 0.7874 -0.4064)
			(stroke
				(width 0.1524)
				(type default)
			)
			(layer "F.SilkS")
		)
		(fp_line
			(start 0.7874 -0.4064)
			(end 0.7874 0.4064)
			(stroke
				(width 0.1524)
				(type default)
			)
			(layer "F.SilkS")
		)
		(fp_line
			(start -0.67945 0.3048)
			(end -0.67945 -0.305054)
			(stroke
				(width 0.1)
				(type default)
			)
			(layer "F.Fab")
		)
		(fp_line
			(start -0.12065 0.3048)
			(end -0.67945 0.3048)
			(stroke
				(width 0.1)
				(type default)
			)
			(layer "F.Fab")
		)
		(fp_line
			(start 0.120396 0.3048)
			(end 0.120396 0.2794)
			(stroke
				(width 0.1)
				(type default)
			)
			(layer "F.Fab")
		)
		(fp_line
			(start 0.67945 0.3048)
			(end 0.120396 0.3048)
			(stroke
				(width 0.1)
				(type default)
			)
			(layer "F.Fab")
		)
		(fp_line
			(start -0.12065 0.2794)
			(end -0.12065 0.3048)
			(stroke
				(width 0.1)
				(type default)
			)
			(layer "F.Fab")
		)
		(fp_line
			(start 0.120396 0.2794)
			(end -0.12065 0.2794)
			(stroke
				(width 0.1)
				(type default)
			)
			(layer "F.Fab")
		)
		(fp_line
			(start -0.12065 -0.2794)
			(end 0.12065 -0.2794)
			(stroke
				(width 0.1)
				(type default)
			)
			(layer "F.Fab")
		)
		(fp_line
			(start 0.12065 -0.2794)
			(end 0.12065 -0.3048)
			(stroke
				(width 0.1)
				(type default)
			)
			(layer "F.Fab")
		)
		(fp_line
			(start 0.12065 -0.3048)
			(end 0.67945 -0.3048)
			(stroke
				(width 0.1)
				(type default)
			)
			(layer "F.Fab")
		)
		(fp_line
			(start 0.67945 -0.3048)
			(end 0.67945 0.3048)
			(stroke
				(width 0.1)
				(type default)
			)
			(layer "F.Fab")
		)
		(fp_line
			(start -0.67945 -0.305054)
			(end -0.12065 -0.305054)
			(stroke
				(width 0.1)
				(type default)
			)
			(layer "F.Fab")
		)
		(fp_line
			(start -0.12065 -0.305054)
			(end -0.12065 -0.2794)
			(stroke
				(width 0.1)
				(type default)
			)
			(layer "F.Fab")
		)
		(pad "1" smd circle
			(at -0.40005 0 270)
			(size 0 0)
			(layers "F.Cu" "F.Mask" "F.Paste")
			(net "ESPI_LAD0_DATA_IO3")
		)
		(pad "2" smd circle
			(at 0.40005 0 270)
			(size 0 0)
			(layers "F.Cu" "F.Mask" "F.Paste")
			(net "ESPI_LPC_LAD0_IO3")
		)
	)
	(footprint ""
		(layer "F.Cu")
		(at 69.16928 -53.548788 180)
		(property "Reference" "PC2168"
			(at 0 0 180)
			(layer "F.SilkS")
			(hide yes)
			(effects
				(font
					(size 1.27 1.27)
				)
			)
		)
		(property "Value" ""
			(at 0 0 180)
			(layer "F.Fab")
			(effects
				(font
					(size 1.27 1.27)
				)
			)
		)
		(duplicate_pad_numbers_are_jumpers no)
		(fp_line
			(start 0.7874 0.4064)
			(end -0.7874 0.4064)
			(stroke
				(width 0.1524)
				(type default)
			)
			(layer "F.SilkS")
		)
		(fp_line
			(start 0.7874 -0.4064)
			(end 0.7874 0.4064)
			(stroke
				(width 0.1524)
				(type default)
			)
			(layer "F.SilkS")
		)
		(fp_line
			(start -0.7874 0.4064)
			(end -0.7874 -0.4064)
			(stroke
				(width 0.1524)
				(type default)
			)
			(layer "F.SilkS")
		)
		(fp_line
			(start -0.7874 -0.4064)
			(end 0.7874 -0.4064)
			(stroke
				(width 0.1524)
				(type default)
			)
			(layer "F.SilkS")
		)
		(fp_line
			(start 0.67945 0.3048)
			(end 0.120396 0.3048)
			(stroke
				(width 0.1)
				(type default)
			)
			(layer "F.Fab")
		)
		(fp_line
			(start 0.67945 -0.3048)
			(end 0.67945 0.3048)
			(stroke
				(width 0.1)
				(type default)
			)
			(layer "F.Fab")
		)
		(fp_line
			(start 0.12065 -0.2794)
			(end 0.12065 -0.3048)
			(stroke
				(width 0.1)
				(type default)
			)
			(layer "F.Fab")
		)
		(fp_line
			(start 0.12065 -0.3048)
			(end 0.67945 -0.3048)
			(stroke
				(width 0.1)
				(type default)
			)
			(layer "F.Fab")
		)
		(fp_line
			(start 0.120396 0.3048)
			(end 0.120396 0.2794)
			(stroke
				(width 0.1)
				(type default)
			)
			(layer "F.Fab")
		)
		(fp_line
			(start 0.120396 0.2794)
			(end -0.12065 0.2794)
			(stroke
				(width 0.1)
				(type default)
			)
			(layer "F.Fab")
		)
		(fp_line
			(start -0.12065 0.3048)
			(end -0.67945 0.3048)
			(stroke
				(width 0.1)
				(type default)
			)
			(layer "F.Fab")
		)
		(fp_line
			(start -0.12065 0.2794)
			(end -0.12065 0.3048)
			(stroke
				(width 0.1)
				(type default)
			)
			(layer "F.Fab")
		)
		(fp_line
			(start -0.12065 -0.2794)
			(end 0.12065 -0.2794)
			(stroke
				(width 0.1)
				(type default)
			)
			(layer "F.Fab")
		)
		(fp_line
			(start -0.12065 -0.305054)
			(end -0.12065 -0.2794)
			(stroke
				(width 0.1)
				(type default)
			)
			(layer "F.Fab")
		)
		(fp_line
			(start -0.67945 0.3048)
			(end -0.67945 -0.305054)
			(stroke
				(width 0.1)
				(type default)
			)
			(layer "F.Fab")
		)
		(fp_line
			(start -0.67945 -0.305054)
			(end -0.12065 -0.305054)
			(stroke
				(width 0.1)
				(type default)
			)
			(layer "F.Fab")
		)
		(pad "1" smd circle
			(at -0.40005 0 180)
			(size 0 0)
			(layers "F.Cu" "F.Mask" "F.Paste")
			(net "P3V3_OCP_MODE_2")
		)
		(pad "2" smd circle
			(at 0.40005 0 180)
			(size 0 0)
			(layers "F.Cu" "F.Mask" "F.Paste")
			(net "GND")
		)
	)
	(footprint ""
		(layer "F.Cu")
		(at 72.4662 -34.788348 180)
		(property "Reference" "R3568"
			(at 0 0 180)
			(layer "F.SilkS")
			(hide yes)
			(effects
				(font
					(size 1.27 1.27)
				)
			)
		)
		(property "Value" ""
			(at 0 0 180)
			(layer "F.Fab")
			(effects
				(font
					(size 1.27 1.27)
				)
			)
		)
		(duplicate_pad_numbers_are_jumpers no)
		(fp_line
			(start 0.7874 0.4064)
			(end -0.7874 0.4064)
			(stroke
				(width 0.1524)
				(type default)
			)
			(layer "F.SilkS")
		)
		(fp_line
			(start 0.7874 -0.4064)
			(end 0.7874 0.4064)
			(stroke
				(width 0.1524)
				(type default)
			)
			(layer "F.SilkS")
		)
		(fp_line
			(start -0.7874 0.4064)
			(end -0.7874 -0.4064)
			(stroke
				(width 0.1524)
				(type default)
			)
			(layer "F.SilkS")
		)
		(fp_line
			(start -0.7874 -0.4064)
			(end 0.7874 -0.4064)
			(stroke
				(width 0.1524)
				(type default)
			)
			(layer "F.SilkS")
		)
		(fp_line
			(start 0.67945 0.3048)
			(end 0.120396 0.3048)
			(stroke
				(width 0.1)
				(type default)
			)
			(layer "F.Fab")
		)
		(fp_line
			(start 0.67945 -0.3048)
			(end 0.67945 0.3048)
			(stroke
				(width 0.1)
				(type default)
			)
			(layer "F.Fab")
		)
		(fp_line
			(start 0.12065 -0.2794)
			(end 0.12065 -0.3048)
			(stroke
				(width 0.1)
				(type default)
			)
			(layer "F.Fab")
		)
		(fp_line
			(start 0.12065 -0.3048)
			(end 0.67945 -0.3048)
			(stroke
				(width 0.1)
				(type default)
			)
			(layer "F.Fab")
		)
		(fp_line
			(start 0.120396 0.3048)
			(end 0.120396 0.2794)
			(stroke
				(width 0.1)
				(type default)
			)
			(layer "F.Fab")
		)
		(fp_line
			(start 0.120396 0.2794)
			(end -0.12065 0.2794)
			(stroke
				(width 0.1)
				(type default)
			)
			(layer "F.Fab")
		)
		(fp_line
			(start -0.12065 0.3048)
			(end -0.67945 0.3048)
			(stroke
				(width 0.1)
				(type default)
			)
			(layer "F.Fab")
		)
		(fp_line
			(start -0.12065 0.2794)
			(end -0.12065 0.3048)
			(stroke
				(width 0.1)
				(type default)
			)
			(layer "F.Fab")
		)
		(fp_line
			(start -0.12065 -0.2794)
			(end 0.12065 -0.2794)
			(stroke
				(width 0.1)
				(type default)
			)
			(layer "F.Fab")
		)
		(fp_line
			(start -0.12065 -0.305054)
			(end -0.12065 -0.2794)
			(stroke
				(width 0.1)
				(type default)
			)
			(layer "F.Fab")
		)
		(fp_line
			(start -0.67945 0.3048)
			(end -0.67945 -0.305054)
			(stroke
				(width 0.1)
				(type default)
			)
			(layer "F.Fab")
		)
		(fp_line
			(start -0.67945 -0.305054)
			(end -0.12065 -0.305054)
			(stroke
				(width 0.1)
				(type default)
			)
			(layer "F.Fab")
		)
		(pad "1" smd circle
			(at -0.40005 0 180)
			(size 0 0)
			(layers "F.Cu" "F.Mask" "F.Paste")
			(net "SMB_INA230_3_3V3AUX_SCL_R")
		)
		(pad "2" smd circle
			(at 0.40005 0 180)
			(size 0 0)
			(layers "F.Cu" "F.Mask" "F.Paste")
			(net "SMB_INA230_3_3V3AUX_SCL_R1")
		)
	)
)
